(kicad_pcb
	(version 20260206)
	(generator "pcbnew")
	(generator_version "10.0")
	(general
		(thickness 1.6)
		(legacy_teardrops no)
	)
	(paper "A4")
	(title_block
		(title "Wiwynn_Tioga_Pass_MB.brd")
		(comment 1 "Tioga Pass / footprints 1971-1977 of 4770")
	)
	(layers
		(0 "F.Cu" signal "TOP")
		(4 "In1.Cu" signal "L2GND")
		(6 "In2.Cu" signal "L3")
		(8 "In3.Cu" signal "L4GND")
		(10 "In4.Cu" signal "L5")
		(12 "In5.Cu" signal "L6GND")
		(14 "In6.Cu" signal "L7VCC")
		(16 "In7.Cu" signal "L8VCC")
		(18 "In8.Cu" signal "L9GND")
		(20 "In9.Cu" signal "L10")
		(22 "In10.Cu" signal "L11GND")
		(24 "In11.Cu" signal "L12")
		(26 "In12.Cu" signal "L13GND")
		(2 "B.Cu" signal "BOTTOM")
		(9 "F.Adhes" user "F.Adhesive")
		(11 "B.Adhes" user "B.Adhesive")
		(13 "F.Paste" user "Package Geometry/Pastemask Top")
		(15 "B.Paste" user "Package Geometry/Pastemask Bottom")
		(5 "F.SilkS" user "Ref Des/Silkscreen Top")
		(7 "B.SilkS" user "Ref Des/Silkscreen Bottom")
		(1 "F.Mask" user "Board Geometry/Soldermask Top")
		(3 "B.Mask" user "Board Geometry/Soldermask Bottom")
		(17 "Dwgs.User" user "User.Drawings")
		(19 "Cmts.User" user "User.Comments")
		(21 "Eco1.User" user "User.Eco1")
		(23 "Eco2.User" user "User.Eco2")
		(25 "Edge.Cuts" user "Board Geometry/Outline")
		(27 "Margin" user)
		(31 "F.CrtYd" user "Package Geometry/Place Bound Top")
		(29 "B.CrtYd" user "Package Geometry/Place Bound Bottom")
		(35 "F.Fab" user "Ref Des/Assembly Top")
		(33 "B.Fab" user "Ref Des/Assembly Bottom")
	)
	(footprint ""
		(layer "F.Cu")
		(at 174.6377 -70.612 -90)
		(property "Reference" "R4D47"
			(at 0 0 270)
			(layer "F.SilkS")
			(hide yes)
			(effects
				(font
					(size 1.27 1.27)
				)
			)
		)
		(property "Value" ""
			(at 0 0 270)
			(layer "F.Fab")
			(effects
				(font
					(size 1.27 1.27)
				)
			)
		)
		(duplicate_pad_numbers_are_jumpers no)
		(fp_poly
			(pts
				(xy -0.2794 -0.1016) (xy 0.2794 -0.1016) (xy 0.2794 0.9906) (xy -0.2794 0.9906)
			)
			(stroke
				(width 0)
				(type default)
			)
			(fill no)
			(layer "F.CrtYd")
		)
		(fp_line
			(start -0.2794 0.9906)
			(end 0.2794 0.9906)
			(stroke
				(width 0.1)
				(type default)
			)
			(layer "F.Fab")
		)
		(fp_line
			(start 0.2794 0.9906)
			(end 0.2794 -0.1016)
			(stroke
				(width 0.1)
				(type default)
			)
			(layer "F.Fab")
		)
		(fp_line
			(start -0.2794 -0.1016)
			(end -0.2794 0.9906)
			(stroke
				(width 0.1)
				(type default)
			)
			(layer "F.Fab")
		)
		(fp_line
			(start 0.2794 -0.1016)
			(end -0.2794 -0.1016)
			(stroke
				(width 0.1)
				(type default)
			)
			(layer "F.Fab")
		)
		(pad "1" smd rect
			(at 0 0 270)
			(size 0.508 0.508)
			(layers "F.Cu" "F.Mask" "F.Paste")
			(net "P3V3_STBY")
		)
		(pad "2" smd rect
			(at 0 0.889 270)
			(size 0.508 0.508)
			(layers "F.Cu" "F.Mask" "F.Paste")
			(net "VR_PVCCIO_CPU1_VDD")
		)
		(zone
			(layer "F.Cu")
			(hatch none 0.5)
			(connect_pads
				(clearance 0)
			)
			(min_thickness 0.25)
			(keepout
				(tracks not_allowed)
				(vias allowed)
				(pads allowed)
				(copperpour not_allowed)
				(footprints allowed)
			)
			(placement
				(enabled no)
				(sheetname "")
			)
			(fill
				(thermal_gap 0.5)
				(thermal_bridge_width 0.5)
				(island_removal_mode 0)
			)
			(polygon
				(pts
					(xy 174.0027 -70.866) (xy 174.0027 -70.358) (xy 174.3837 -70.358) (xy 174.3837 -70.866)
				)
			)
		)
		(zone
			(layer "F.Cu")
			(hatch none 0.5)
			(connect_pads
				(clearance 0)
			)
			(min_thickness 0.25)
			(keepout
				(tracks allowed)
				(vias not_allowed)
				(pads allowed)
				(copperpour not_allowed)
				(footprints allowed)
			)
			(placement
				(enabled no)
				(sheetname "")
			)
			(fill
				(thermal_gap 0.5)
				(thermal_bridge_width 0.5)
				(island_removal_mode 0)
			)
			(polygon
				(pts
					(xy 174.3837 -70.866) (xy 174.3837 -70.358) (xy 174.0027 -70.358) (xy 174.0027 -70.866)
				)
			)
		)
	)
	(footprint ""
		(layer "F.Cu")
		(at 117.221 -77.089 -90)
		(property "Reference" "R3D9"
			(at 0 0 270)
			(layer "F.SilkS")
			(hide yes)
			(effects
				(font
					(size 1.27 1.27)
				)
			)
		)
		(property "Value" ""
			(at 0 0 270)
			(layer "F.Fab")
			(effects
				(font
					(size 1.27 1.27)
				)
			)
		)
		(duplicate_pad_numbers_are_jumpers no)
		(fp_poly
			(pts
				(xy -0.2794 -0.1016) (xy 0.2794 -0.1016) (xy 0.2794 0.9906) (xy -0.2794 0.9906)
			)
			(stroke
				(width 0)
				(type default)
			)
			(fill no)
			(layer "F.CrtYd")
		)
		(fp_line
			(start -0.2794 0.9906)
			(end 0.2794 0.9906)
			(stroke
				(width 0.1)
				(type default)
			)
			(layer "F.Fab")
		)
		(fp_line
			(start 0.2794 0.9906)
			(end 0.2794 -0.1016)
			(stroke
				(width 0.1)
				(type default)
			)
			(layer "F.Fab")
		)
		(fp_line
			(start -0.2794 -0.1016)
			(end -0.2794 0.9906)
			(stroke
				(width 0.1)
				(type default)
			)
			(layer "F.Fab")
		)
		(fp_line
			(start 0.2794 -0.1016)
			(end -0.2794 -0.1016)
			(stroke
				(width 0.1)
				(type default)
			)
			(layer "F.Fab")
		)
		(pad "1" smd rect
			(at 0 0 270)
			(size 0.508 0.508)
			(layers "F.Cu" "F.Mask" "F.Paste")
			(net "PD_CPU1_TEST12")
		)
		(pad "2" smd rect
			(at 0 0.889 270)
			(size 0.508 0.508)
			(layers "F.Cu" "F.Mask" "F.Paste")
			(net "GND")
		)
		(zone
			(layer "F.Cu")
			(hatch none 0.5)
			(connect_pads
				(clearance 0)
			)
			(min_thickness 0.25)
			(keepout
				(tracks not_allowed)
				(vias allowed)
				(pads allowed)
				(copperpour not_allowed)
				(footprints allowed)
			)
			(placement
				(enabled no)
				(sheetname "")
			)
			(fill
				(thermal_gap 0.5)
				(thermal_bridge_width 0.5)
				(island_removal_mode 0)
			)
			(polygon
				(pts
					(xy 116.586 -77.343) (xy 116.586 -76.835) (xy 116.967 -76.835) (xy 116.967 -77.343)
				)
			)
		)
		(zone
			(layer "F.Cu")
			(hatch none 0.5)
			(connect_pads
				(clearance 0)
			)
			(min_thickness 0.25)
			(keepout
				(tracks allowed)
				(vias not_allowed)
				(pads allowed)
				(copperpour not_allowed)
				(footprints allowed)
			)
			(placement
				(enabled no)
				(sheetname "")
			)
			(fill
				(thermal_gap 0.5)
				(thermal_bridge_width 0.5)
				(island_removal_mode 0)
			)
			(polygon
				(pts
					(xy 116.967 -77.343) (xy 116.967 -76.835) (xy 116.586 -76.835) (xy 116.586 -77.343)
				)
			)
		)
	)
	(footprint ""
		(layer "F.Cu")
		(at 494.1697 -125.03912 90)
		(property "Reference" "R1M8"
			(at 0 0 90)
			(layer "F.SilkS")
			(hide yes)
			(effects
				(font
					(size 1.27 1.27)
				)
			)
		)
		(property "Value" ""
			(at 0 0 90)
			(layer "F.Fab")
			(effects
				(font
					(size 1.27 1.27)
				)
			)
		)
		(duplicate_pad_numbers_are_jumpers no)
		(fp_rect
			(start 0.2794 -0.1016)
			(end -0.2794 0.9906)
			(stroke
				(width 0)
				(type default)
			)
			(fill no)
			(layer "F.CrtYd")
		)
		(fp_line
			(start 0.2794 -0.1016)
			(end -0.2794 -0.1016)
			(stroke
				(width 0.1)
				(type default)
			)
			(layer "F.Fab")
		)
		(fp_line
			(start -0.2794 -0.1016)
			(end -0.2794 0.9906)
			(stroke
				(width 0.1)
				(type default)
			)
			(layer "F.Fab")
		)
		(fp_line
			(start 0.2794 0.9906)
			(end 0.2794 -0.1016)
			(stroke
				(width 0.1)
				(type default)
			)
			(layer "F.Fab")
		)
		(fp_line
			(start -0.2794 0.9906)
			(end 0.2794 0.9906)
			(stroke
				(width 0.1)
				(type default)
			)
			(layer "F.Fab")
		)
		(pad "1" smd rect
			(at 0 0 90)
			(size 0.508 0.508)
			(layers "F.Cu" "F.Mask" "F.Paste")
			(net "SMB_SENSOR_TMP421_1_SCL")
		)
		(pad "2" smd rect
			(at 0 0.889 90)
			(size 0.508 0.508)
			(layers "F.Cu" "F.Mask" "F.Paste")
			(net "SMB_SENSOR_STBY_LVC3_SCL")
		)
		(zone
			(layer "F.Cu")
			(hatch none 0.5)
			(connect_pads
				(clearance 0)
			)
			(min_thickness 0.25)
			(keepout
				(tracks not_allowed)
				(vias allowed)
				(pads allowed)
				(copperpour not_allowed)
				(footprints allowed)
			)
			(placement
				(enabled no)
				(sheetname "")
			)
			(fill
				(thermal_gap 0.5)
				(thermal_bridge_width 0.5)
				(island_removal_mode 0)
			)
			(polygon
				(pts
					(xy 494.4237 -125.29312) (xy 494.4237 -124.78512) (xy 494.8047 -124.78512) (xy 494.8047 -125.29312)
				)
			)
		)
		(zone
			(layer "F.Cu")
			(hatch none 0.5)
			(connect_pads
				(clearance 0)
			)
			(min_thickness 0.25)
			(keepout
				(tracks allowed)
				(vias not_allowed)
				(pads allowed)
				(copperpour not_allowed)
				(footprints allowed)
			)
			(placement
				(enabled no)
				(sheetname "")
			)
			(fill
				(thermal_gap 0.5)
				(thermal_bridge_width 0.5)
				(island_removal_mode 0)
			)
			(polygon
				(pts
					(xy 494.4237 -125.29312) (xy 494.4237 -124.78512) (xy 494.8047 -124.78512) (xy 494.8047 -125.29312)
				)
			)
		)
	)
	(footprint ""
		(layer "F.Cu")
		(at 411.327092 -125.850904 -90)
		(property "Reference" "R8B14"
			(at 0 0 270)
			(layer "F.SilkS")
			(hide yes)
			(effects
				(font
					(size 1.27 1.27)
				)
			)
		)
		(property "Value" ""
			(at 0 0 270)
			(layer "F.Fab")
			(effects
				(font
					(size 1.27 1.27)
				)
			)
		)
		(duplicate_pad_numbers_are_jumpers no)
		(fp_poly
			(pts
				(xy -0.2794 -0.1016) (xy 0.2794 -0.1016) (xy 0.2794 0.9906) (xy -0.2794 0.9906)
			)
			(stroke
				(width 0)
				(type default)
			)
			(fill no)
			(layer "F.CrtYd")
		)
		(fp_line
			(start -0.2794 0.9906)
			(end 0.2794 0.9906)
			(stroke
				(width 0.1)
				(type default)
			)
			(layer "F.Fab")
		)
		(fp_line
			(start 0.2794 0.9906)
			(end 0.2794 -0.1016)
			(stroke
				(width 0.1)
				(type default)
			)
			(layer "F.Fab")
		)
		(fp_line
			(start -0.2794 -0.1016)
			(end -0.2794 0.9906)
			(stroke
				(width 0.1)
				(type default)
			)
			(layer "F.Fab")
		)
		(fp_line
			(start 0.2794 -0.1016)
			(end -0.2794 -0.1016)
			(stroke
				(width 0.1)
				(type default)
			)
			(layer "F.Fab")
		)
		(pad "1" smd rect
			(at 0 0 270)
			(size 0.508 0.508)
			(layers "F.Cu" "F.Mask" "F.Paste")
			(net "VSENSE_P1V05_PCH_STBY_AVSP")
		)
		(pad "2" smd rect
			(at 0 0.889 270)
			(size 0.508 0.508)
			(layers "F.Cu" "F.Mask" "F.Paste")
			(net "P1V05_PCH_STBY")
		)
		(zone
			(layer "F.Cu")
			(hatch none 0.5)
			(connect_pads
				(clearance 0)
			)
			(min_thickness 0.25)
			(keepout
				(tracks not_allowed)
				(vias allowed)
				(pads allowed)
				(copperpour not_allowed)
				(footprints allowed)
			)
			(placement
				(enabled no)
				(sheetname "")
			)
			(fill
				(thermal_gap 0.5)
				(thermal_bridge_width 0.5)
				(island_removal_mode 0)
			)
			(polygon
				(pts
					(xy 410.692092 -126.104904) (xy 410.692092 -125.596904) (xy 411.073092 -125.596904) (xy 411.073092 -126.104904)
				)
			)
		)
		(zone
			(layer "F.Cu")
			(hatch none 0.5)
			(connect_pads
				(clearance 0)
			)
			(min_thickness 0.25)
			(keepout
				(tracks allowed)
				(vias not_allowed)
				(pads allowed)
				(copperpour not_allowed)
				(footprints allowed)
			)
			(placement
				(enabled no)
				(sheetname "")
			)
			(fill
				(thermal_gap 0.5)
				(thermal_bridge_width 0.5)
				(island_removal_mode 0)
			)
			(polygon
				(pts
					(xy 411.073092 -126.104904) (xy 411.073092 -125.596904) (xy 410.692092 -125.596904) (xy 410.692092 -126.104904)
				)
			)
		)
	)
	(footprint ""
		(layer "F.Cu")
		(at 195.4784 -140.0556 90)
		(property "Reference" "C4A18"
			(at 0 0 90)
			(layer "F.SilkS")
			(hide yes)
			(effects
				(font
					(size 1.27 1.27)
				)
			)
		)
		(property "Value" ""
			(at 0 0 90)
			(layer "F.Fab")
			(effects
				(font
					(size 1.27 1.27)
				)
			)
		)
		(duplicate_pad_numbers_are_jumpers no)
		(fp_poly
			(pts
				(xy 0.3048 -0.1016) (xy 0.3048 0.9906) (xy -0.3048 0.9906) (xy -0.3048 -0.1016)
			)
			(stroke
				(width 0)
				(type default)
			)
			(fill no)
			(layer "F.CrtYd")
		)
		(fp_line
			(start 0.3048 -0.1016)
			(end -0.3048 -0.1016)
			(stroke
				(width 0.1)
				(type default)
			)
			(layer "F.Fab")
		)
		(fp_line
			(start -0.3048 -0.1016)
			(end -0.3048 0.9906)
			(stroke
				(width 0.1)
				(type default)
			)
			(layer "F.Fab")
		)
		(fp_line
			(start 0.3048 0.9906)
			(end 0.3048 -0.1016)
			(stroke
				(width 0.1)
				(type default)
			)
			(layer "F.Fab")
		)
		(fp_line
			(start -0.3048 0.9906)
			(end 0.3048 0.9906)
			(stroke
				(width 0.1)
				(type default)
			)
			(layer "F.Fab")
		)
		(pad "1" smd rect
			(at 0 0 90)
			(size 0.508 0.508)
			(layers "F.Cu" "F.Mask" "F.Paste")
			(net "M_E_VREF")
		)
		(pad "2" smd rect
			(at 0 0.889 90)
			(size 0.508 0.508)
			(layers "F.Cu" "F.Mask" "F.Paste")
			(net "GND")
		)
		(zone
			(layer "F.Cu")
			(hatch none 0.5)
			(connect_pads
				(clearance 0)
			)
			(min_thickness 0.25)
			(keepout
				(tracks allowed)
				(vias not_allowed)
				(pads allowed)
				(copperpour not_allowed)
				(footprints allowed)
			)
			(placement
				(enabled no)
				(sheetname "")
			)
			(fill
				(thermal_gap 0.5)
				(thermal_bridge_width 0.5)
				(island_removal_mode 0)
			)
			(polygon
				(pts
					(xy 195.7324 -139.8016) (xy 195.7324 -140.3096) (xy 196.1134 -140.3096) (xy 196.1134 -139.8016)
				)
			)
		)
		(zone
			(layer "F.Cu")
			(hatch none 0.5)
			(connect_pads
				(clearance 0)
			)
			(min_thickness 0.25)
			(keepout
				(tracks not_allowed)
				(vias allowed)
				(pads allowed)
				(copperpour not_allowed)
				(footprints allowed)
			)
			(placement
				(enabled no)
				(sheetname "")
			)
			(fill
				(thermal_gap 0.5)
				(thermal_bridge_width 0.5)
				(island_removal_mode 0)
			)
			(polygon
				(pts
					(xy 196.1134 -139.8016) (xy 196.1134 -140.3096) (xy 195.7324 -140.3096) (xy 195.7324 -139.8016)
				)
			)
		)
	)
	(footprint ""
		(layer "F.Cu")
		(at 1.27 -75.057 180)
		(property "Reference" "R9R7"
			(at 0 0 180)
			(layer "F.SilkS")
			(hide yes)
			(effects
				(font
					(size 1.27 1.27)
				)
			)
		)
		(property "Value" ""
			(at 0 0 180)
			(layer "F.Fab")
			(effects
				(font
					(size 1.27 1.27)
				)
			)
		)
		(duplicate_pad_numbers_are_jumpers no)
		(fp_poly
			(pts
				(xy -0.2794 -0.1016) (xy 0.2794 -0.1016) (xy 0.2794 0.9906) (xy -0.2794 0.9906)
			)
			(stroke
				(width 0)
				(type default)
			)
			(fill no)
			(layer "F.CrtYd")
		)
		(fp_line
			(start 0.2794 0.9906)
			(end 0.2794 -0.1016)
			(stroke
				(width 0.1)
				(type default)
			)
			(layer "F.Fab")
		)
		(fp_line
			(start 0.2794 -0.1016)
			(end -0.2794 -0.1016)
			(stroke
				(width 0.1)
				(type default)
			)
			(layer "F.Fab")
		)
		(fp_line
			(start -0.2794 0.9906)
			(end 0.2794 0.9906)
			(stroke
				(width 0.1)
				(type default)
			)
			(layer "F.Fab")
		)
		(fp_line
			(start -0.2794 -0.1016)
			(end -0.2794 0.9906)
			(stroke
				(width 0.1)
				(type default)
			)
			(layer "F.Fab")
		)
		(pad "1" smd rect
			(at 0 0 180)
			(size 0.508 0.508)
			(layers "F.Cu" "F.Mask" "F.Paste")
			(net "SMB_SENSOR_TMP421_2_SCL")
		)
		(pad "2" smd rect
			(at 0 0.889 180)
			(size 0.508 0.508)
			(layers "F.Cu" "F.Mask" "F.Paste")
			(net "SMB_SENSOR_STBY_LVC3_SCL")
		)
		(zone
			(layer "F.Cu")
			(hatch none 0.5)
			(connect_pads
				(clearance 0)
			)
			(min_thickness 0.25)
			(keepout
				(tracks not_allowed)
				(vias allowed)
				(pads allowed)
				(copperpour not_allowed)
				(footprints allowed)
			)
			(placement
				(enabled no)
				(sheetname "")
			)
			(fill
				(thermal_gap 0.5)
				(thermal_bridge_width 0.5)
				(island_removal_mode 0)
			)
			(polygon
				(pts
					(xy 1.524 -75.692) (xy 1.016 -75.692) (xy 1.016 -75.311) (xy 1.524 -75.311)
				)
			)
		)
		(zone
			(layer "F.Cu")
			(hatch none 0.5)
			(connect_pads
				(clearance 0)
			)
			(min_thickness 0.25)
			(keepout
				(tracks allowed)
				(vias not_allowed)
				(pads allowed)
				(copperpour not_allowed)
				(footprints allowed)
			)
			(placement
				(enabled no)
				(sheetname "")
			)
			(fill
				(thermal_gap 0.5)
				(thermal_bridge_width 0.5)
				(island_removal_mode 0)
			)
			(polygon
				(pts
					(xy 1.524 -75.311) (xy 1.016 -75.311) (xy 1.016 -75.692) (xy 1.524 -75.692)
				)
			)
		)
	)
	(footprint ""
		(layer "F.Cu")
		(at 377.698 -87.3125 180)
		(property "Reference" "R3N17"
			(at -0.8382 -0.67818 180)
			(unlocked yes)
			(layer "F.SilkS")
			(effects
				(font
					(size 0.4064 0.254)
					(thickness 0.1524)
				)
				(justify left)
			)
		)
		(property "Value" ""
			(at 0 0 180)
			(layer "F.Fab")
			(effects
				(font
					(size 1.27 1.27)
				)
			)
		)
		(duplicate_pad_numbers_are_jumpers no)
		(fp_poly
			(pts
				(xy -0.2794 -0.1016) (xy 0.2794 -0.1016) (xy 0.2794 0.9906) (xy -0.2794 0.9906)
			)
			(stroke
				(width 0)
				(type default)
			)
			(fill no)
			(layer "F.CrtYd")
		)
		(fp_line
			(start 0.2794 0.9906)
			(end 0.2794 -0.1016)
			(stroke
				(width 0.1)
				(type default)
			)
			(layer "F.Fab")
		)
		(fp_line
			(start 0.2794 -0.1016)
			(end -0.2794 -0.1016)
			(stroke
				(width 0.1)
				(type default)
			)
			(layer "F.Fab")
		)
		(fp_line
			(start -0.2794 0.9906)
			(end 0.2794 0.9906)
			(stroke
				(width 0.1)
				(type default)
			)
			(layer "F.Fab")
		)
		(fp_line
			(start -0.2794 -0.1016)
			(end -0.2794 0.9906)
			(stroke
				(width 0.1)
				(type default)
			)
			(layer "F.Fab")
		)
		(pad "1" smd rect
			(at 0 0 180)
			(size 0.508 0.508)
			(layers "F.Cu" "F.Mask" "F.Paste")
			(net "P3V3_STBY")
		)
		(pad "2" smd rect
			(at 0 0.889 180)
			(size 0.508 0.508)
			(layers "F.Cu" "F.Mask" "F.Paste")
			(net "SPI_PCH_IO3")
		)
		(zone
			(layer "F.Cu")
			(hatch none 0.5)
			(connect_pads
				(clearance 0)
			)
			(min_thickness 0.25)
			(keepout
				(tracks not_allowed)
				(vias allowed)
				(pads allowed)
				(copperpour not_allowed)
				(footprints allowed)
			)
			(placement
				(enabled no)
				(sheetname "")
			)
			(fill
				(thermal_gap 0.5)
				(thermal_bridge_width 0.5)
				(island_removal_mode 0)
			)
			(polygon
				(pts
					(xy 377.952 -87.9475) (xy 377.444 -87.9475) (xy 377.444 -87.5665) (xy 377.952 -87.5665)
				)
			)
		)
		(zone
			(layer "F.Cu")
			(hatch none 0.5)
			(connect_pads
				(clearance 0)
			)
			(min_thickness 0.25)
			(keepout
				(tracks allowed)
				(vias not_allowed)
				(pads allowed)
				(copperpour not_allowed)
				(footprints allowed)
			)
			(placement
				(enabled no)
				(sheetname "")
			)
			(fill
				(thermal_gap 0.5)
				(thermal_bridge_width 0.5)
				(island_removal_mode 0)
			)
			(polygon
				(pts
					(xy 377.952 -87.5665) (xy 377.444 -87.5665) (xy 377.444 -87.9475) (xy 377.952 -87.9475)
				)
			)
		)
	)
)
